(kicad_pcb
	(version 20260206)
	(generator "pcbnew")
	(generator_version "10.0")
	(general
		(thickness 1.6)
		(legacy_teardrops no)
	)
	(paper "A4")
	(title_block
		(title "04192023_DAF0TMB3IC0_F0TG_MB_C_brd_V02_OCP.brd")
		(comment 1 "Grand Teton / footprint 2783 of 8354 (U26), pads 2449-2560 of 6102")
	)
	(layers
		(0 "F.Cu" signal "TOP")
		(4 "In1.Cu" signal "GND")
		(6 "In2.Cu" signal "IN1")
		(8 "In3.Cu" signal "GND1")
		(10 "In4.Cu" signal "IN2")
		(12 "In5.Cu" signal "GND2")
		(14 "In6.Cu" signal "IN3")
		(16 "In7.Cu" signal "GND3")
		(18 "In8.Cu" signal "VCC")
		(20 "In9.Cu" signal "VCC1")
		(22 "In10.Cu" signal "GND4")
		(24 "In11.Cu" signal "IN4")
		(26 "In12.Cu" signal "GND5")
		(28 "In13.Cu" signal "IN5")
		(30 "In14.Cu" signal "GND6")
		(32 "In15.Cu" signal "IN6")
		(34 "In16.Cu" signal "GND7")
		(2 "B.Cu" signal "BOTTOM")
		(9 "F.Adhes" user "F.Adhesive")
		(11 "B.Adhes" user "B.Adhesive")
		(13 "F.Paste" user "Package Geometry/Pastemask Top")
		(15 "B.Paste" user "Package Geometry/Pastemask Bottom")
		(5 "F.SilkS" user "Ref Des/Silkscreen Top")
		(7 "B.SilkS" user "Ref Des/Silkscreen Bottom")
		(1 "F.Mask" user "Board Geometry/Soldermask Top")
		(3 "B.Mask" user "Board Geometry/Soldermask Bottom")
		(17 "Dwgs.User" user "User.Drawings")
		(19 "Cmts.User" user "User.Comments")
		(21 "Eco1.User" user "User.Eco1")
		(23 "Eco2.User" user "User.Eco2")
		(25 "Edge.Cuts" user "Board Geometry/Outline")
		(27 "Margin" user)
		(31 "F.CrtYd" user "Package Geometry/Place Bound Top")
		(29 "B.CrtYd" user "Package Geometry/Place Bound Bottom")
		(35 "F.Fab" user "Ref Des/Assembly Top")
		(33 "B.Fab" user "Ref Des/Assembly Bottom")
	)
	(footprint ""
		(layer "F.Cu")
		(at 111.927894 -258.880356 180)
		(property "Reference" "U26"
			(at -45.05579 -61.794136 0)
			(unlocked yes)
			(layer "F.SilkS")
			(effects
				(font
					(size 0.7874 0.5842)
					(thickness 0.1524)
				)
			)
		)
		(property "Value" ""
			(at 0 0 180)
			(layer "F.Fab")
			(effects
				(font
					(size 1.27 1.27)
				)
			)
		)
		(duplicate_pad_numbers_are_jumpers no)
		(pad "BU1" smd circle
			(at -34.459926 10.889996 180)
			(size 0.450088 0.450088)
			(layers "F.Cu" "F.Mask" "F.Paste")
			(net "GND")
		)
		(pad "BU2" smd circle
			(at -33.519872 10.889996 180)
			(size 0.450088 0.450088)
			(layers "F.Cu" "F.Mask" "F.Paste")
			(net "M_G_CPU1_SB_CB<6>")
		)
		(pad "BU3" smd circle
			(at -32.580072 10.889996 180)
			(size 0.450088 0.450088)
			(layers "F.Cu" "F.Mask" "F.Paste")
			(net "M_G_CPU1_SB_CB<5>")
		)
		(pad "BU4" smd circle
			(at -31.640018 10.889996 180)
			(size 0.450088 0.450088)
			(layers "F.Cu" "F.Mask" "F.Paste")
			(net "GND")
		)
		(pad "BU5" smd circle
			(at -30.699964 10.889996 180)
			(size 0.450088 0.450088)
			(layers "F.Cu" "F.Mask" "F.Paste")
			(net "M_K_CPU1_SB_CB<6>")
		)
		(pad "BU6" smd circle
			(at -29.75991 10.889996 180)
			(size 0.450088 0.450088)
			(layers "F.Cu" "F.Mask" "F.Paste")
			(net "GND")
		)
		(pad "BU7" smd circle
			(at -28.82011 10.889996 180)
			(size 0.450088 0.450088)
			(layers "F.Cu" "F.Mask" "F.Paste")
			(net "M_K_CPU1_SB_CB<5>")
		)
		(pad "BU8" smd circle
			(at -27.880056 10.889996 180)
			(size 0.450088 0.450088)
			(layers "F.Cu" "F.Mask" "F.Paste")
			(net "GND")
		)
		(pad "BU9" smd circle
			(at -26.940002 10.889996 180)
			(size 0.450088 0.450088)
			(layers "F.Cu" "F.Mask" "F.Paste")
			(net "M_L_CPU1_SB_CB<6>")
		)
		(pad "BU10" smd circle
			(at -25.999948 10.889996 180)
			(size 0.450088 0.450088)
			(layers "F.Cu" "F.Mask" "F.Paste")
			(net "M_L_CPU1_SB_CB<5>")
		)
		(pad "BU11" smd circle
			(at -25.059894 10.889996 180)
			(size 0.450088 0.450088)
			(layers "F.Cu" "F.Mask" "F.Paste")
			(net "GND")
		)
		(pad "BU12" smd circle
			(at -24.120094 10.889996 180)
			(size 0.450088 0.450088)
			(layers "F.Cu" "F.Mask" "F.Paste")
			(net "M_H_CPU1_SB_CB<6>")
		)
		(pad "BU13" smd circle
			(at -23.18004 10.889996 180)
			(size 0.450088 0.450088)
			(layers "F.Cu" "F.Mask" "F.Paste")
			(net "GND")
		)
		(pad "BU14" smd circle
			(at -22.239986 10.889996 180)
			(size 0.450088 0.450088)
			(layers "F.Cu" "F.Mask" "F.Paste")
			(net "M_H_CPU1_SB_CB<5>")
		)
		(pad "BU15" smd circle
			(at -21.299932 10.889996 180)
			(size 0.450088 0.450088)
			(layers "F.Cu" "F.Mask" "F.Paste")
			(net "GND")
		)
		(pad "BU16" smd circle
			(at -20.359878 10.889996 180)
			(size 0.450088 0.450088)
			(layers "F.Cu" "F.Mask" "F.Paste")
			(net "M_J_CPU1_SB_CB<6>")
		)
		(pad "BU17" smd circle
			(at -19.420078 10.889996 180)
			(size 0.450088 0.450088)
			(layers "F.Cu" "F.Mask" "F.Paste")
			(net "M_J_CPU1_SB_CB<5>")
		)
		(pad "BU18" smd circle
			(at -18.480024 10.889996 180)
			(size 0.450088 0.450088)
			(layers "F.Cu" "F.Mask" "F.Paste")
			(net "GND")
		)
		(pad "BU19" smd circle
			(at -17.53997 10.889996 180)
			(size 0.450088 0.450088)
			(layers "F.Cu" "F.Mask" "F.Paste")
			(net "M_I_CPU1_SB_CB<6>")
		)
		(pad "BU20" smd circle
			(at -16.599916 10.889996 180)
			(size 0.450088 0.450088)
			(layers "F.Cu" "F.Mask" "F.Paste")
			(net "GND")
		)
		(pad "BU21" smd circle
			(at -15.660116 10.889996 180)
			(size 0.450088 0.450088)
			(layers "F.Cu" "F.Mask" "F.Paste")
			(net "M_I_CPU1_SB_CB<5>")
		)
		(pad "BU22" smd circle
			(at -14.720062 10.889996 180)
			(size 0.450088 0.450088)
			(layers "F.Cu" "F.Mask" "F.Paste")
			(net "GND")
		)
		(pad "BU23" smd circle
			(at -13.780008 10.889996 180)
			(size 0.450088 0.450088)
			(layers "F.Cu" "F.Mask" "F.Paste")
			(net "P5E_CPU1_P2_TX_DN<13>")
		)
		(pad "BU24" smd circle
			(at -12.839954 10.889996 180)
			(size 0.450088 0.450088)
			(layers "F.Cu" "F.Mask" "F.Paste")
			(net "P5E_CPU1_P2_TX_DP<13>")
		)
		(pad "BU25" smd circle
			(at -11.8999 10.889996 180)
			(size 0.450088 0.450088)
			(layers "F.Cu" "F.Mask" "F.Paste")
			(net "GND")
		)
		(pad "BU26" smd circle
			(at -10.9601 10.889996 180)
			(size 0.450088 0.450088)
			(layers "F.Cu" "F.Mask" "F.Paste")
			(net "P5E_CPU1_P2_TX_DN<10>")
		)
		(pad "BU27" smd circle
			(at -10.020046 10.889996 180)
			(size 0.450088 0.450088)
			(layers "F.Cu" "F.Mask" "F.Paste")
			(net "P5E_CPU1_P2_TX_DP<10>")
		)
		(pad "BU28" smd circle
			(at -9.079992 10.889996 180)
			(size 0.450088 0.450088)
			(layers "F.Cu" "F.Mask" "F.Paste")
			(net "GND")
		)
		(pad "BU29" smd circle
			(at -8.139938 10.889996 180)
			(size 0.450088 0.450088)
			(layers "F.Cu" "F.Mask" "F.Paste")
			(net "P5E_CPU1_P2_TX_DN<7>")
		)
		(pad "BU30" smd circle
			(at -7.199884 10.889996 180)
			(size 0.450088 0.450088)
			(layers "F.Cu" "F.Mask" "F.Paste")
			(net "P5E_CPU1_P2_TX_DP<7>")
		)
		(pad "BU31" smd circle
			(at -6.260084 10.889996 180)
			(size 0.450088 0.450088)
			(layers "F.Cu" "F.Mask" "F.Paste")
			(net "GND")
		)
		(pad "BU32" smd circle
			(at -5.32003 10.889996 180)
			(size 0.450088 0.450088)
			(layers "F.Cu" "F.Mask" "F.Paste")
			(net "P5E_CPU1_P2_TX_DN<4>")
		)
		(pad "BU33" smd circle
			(at -4.379976 10.889996 180)
			(size 0.450088 0.450088)
			(layers "F.Cu" "F.Mask" "F.Paste")
			(net "P5E_CPU1_P2_TX_DP<4>")
		)
		(pad "BU34" smd circle
			(at -3.439922 10.889996 180)
			(size 0.450088 0.450088)
			(layers "F.Cu" "F.Mask" "F.Paste")
			(net "GND")
		)
		(pad "BU35" smd circle
			(at -2.500122 10.889996 180)
			(size 0.450088 0.450088)
			(layers "F.Cu" "F.Mask" "F.Paste")
			(net "GND")
		)
		(pad "BU36" smd circle
			(at -1.560068 10.889996 180)
			(size 0.450088 0.450088)
			(layers "F.Cu" "F.Mask" "F.Paste")
			(net "GND")
		)
		(pad "BU40" smd circle
			(at 1.260094 10.889996 180)
			(size 0.450088 0.450088)
			(layers "F.Cu" "F.Mask" "F.Paste")
			(net "GND")
		)
		(pad "BU41" smd circle
			(at 2.199894 10.889996 180)
			(size 0.450088 0.450088)
			(layers "F.Cu" "F.Mask" "F.Paste")
			(net "GND")
		)
		(pad "BU42" smd circle
			(at 3.139948 10.889996 180)
			(size 0.450088 0.450088)
			(layers "F.Cu" "F.Mask" "F.Paste")
			(net "GND")
		)
		(pad "BU43" smd circle
			(at 4.080002 10.889996 180)
			(size 0.450088 0.450088)
			(layers "F.Cu" "F.Mask" "F.Paste")
			(net "P5E_CPU1_P0_RX_DP<11>")
		)
		(pad "BU44" smd circle
			(at 5.020056 10.889996 180)
			(size 0.450088 0.450088)
			(layers "F.Cu" "F.Mask" "F.Paste")
			(net "P5E_CPU1_P0_RX_DN<11>")
		)
		(pad "BU45" smd circle
			(at 5.96011 10.889996 180)
			(size 0.450088 0.450088)
			(layers "F.Cu" "F.Mask" "F.Paste")
			(net "GND")
		)
		(pad "BU46" smd circle
			(at 6.89991 10.889996 180)
			(size 0.450088 0.450088)
			(layers "F.Cu" "F.Mask" "F.Paste")
			(net "P5E_CPU1_P0_RX_DP<8>")
		)
		(pad "BU47" smd circle
			(at 7.839964 10.889996 180)
			(size 0.450088 0.450088)
			(layers "F.Cu" "F.Mask" "F.Paste")
			(net "P5E_CPU1_P0_RX_DN<8>")
		)
		(pad "BU48" smd circle
			(at 8.780018 10.889996 180)
			(size 0.450088 0.450088)
			(layers "F.Cu" "F.Mask" "F.Paste")
			(net "GND")
		)
		(pad "BU49" smd circle
			(at 9.720072 10.889996 180)
			(size 0.450088 0.450088)
			(layers "F.Cu" "F.Mask" "F.Paste")
			(net "P5E_CPU1_P0_RX_DP<5>")
		)
		(pad "BU50" smd circle
			(at 10.659872 10.889996 180)
			(size 0.450088 0.450088)
			(layers "F.Cu" "F.Mask" "F.Paste")
			(net "P5E_CPU1_P0_RX_DN<5>")
		)
		(pad "BU51" smd circle
			(at 11.599926 10.889996 180)
			(size 0.450088 0.450088)
			(layers "F.Cu" "F.Mask" "F.Paste")
			(net "GND")
		)
		(pad "BU52" smd circle
			(at 12.53998 10.889996 180)
			(size 0.450088 0.450088)
			(layers "F.Cu" "F.Mask" "F.Paste")
			(net "P5E_CPU1_P0_RX_DP<2>")
		)
		(pad "BU53" smd circle
			(at 13.480034 10.889996 180)
			(size 0.450088 0.450088)
			(layers "F.Cu" "F.Mask" "F.Paste")
			(net "P5E_CPU1_P0_RX_DN<2>")
		)
		(pad "BU54" smd circle
			(at 14.420088 10.889996 180)
			(size 0.450088 0.450088)
			(layers "F.Cu" "F.Mask" "F.Paste")
			(net "GND")
		)
		(pad "BU55" smd circle
			(at 15.359888 10.889996 180)
			(size 0.450088 0.450088)
			(layers "F.Cu" "F.Mask" "F.Paste")
			(net "M_C_CPU1_SB_CB<5>")
		)
		(pad "BU56" smd circle
			(at 16.299942 10.889996 180)
			(size 0.450088 0.450088)
			(layers "F.Cu" "F.Mask" "F.Paste")
			(net "GND")
		)
		(pad "BU57" smd circle
			(at 17.239996 10.889996 180)
			(size 0.450088 0.450088)
			(layers "F.Cu" "F.Mask" "F.Paste")
			(net "M_C_CPU1_SB_CB<6>")
		)
		(pad "BU58" smd circle
			(at 18.18005 10.889996 180)
			(size 0.450088 0.450088)
			(layers "F.Cu" "F.Mask" "F.Paste")
			(net "GND")
		)
		(pad "BU59" smd circle
			(at 19.120104 10.889996 180)
			(size 0.450088 0.450088)
			(layers "F.Cu" "F.Mask" "F.Paste")
			(net "M_D_CPU1_SB_CB<5>")
		)
		(pad "BU60" smd circle
			(at 20.059904 10.889996 180)
			(size 0.450088 0.450088)
			(layers "F.Cu" "F.Mask" "F.Paste")
			(net "M_D_CPU1_SB_CB<6>")
		)
		(pad "BU61" smd circle
			(at 20.999958 10.889996 180)
			(size 0.450088 0.450088)
			(layers "F.Cu" "F.Mask" "F.Paste")
			(net "GND")
		)
		(pad "BU62" smd circle
			(at 21.940012 10.889996 180)
			(size 0.450088 0.450088)
			(layers "F.Cu" "F.Mask" "F.Paste")
			(net "M_B_CPU1_SB_CB<5>")
		)
		(pad "BU63" smd circle
			(at 22.880066 10.889996 180)
			(size 0.450088 0.450088)
			(layers "F.Cu" "F.Mask" "F.Paste")
			(net "GND")
		)
		(pad "BU64" smd circle
			(at 23.82012 10.889996 180)
			(size 0.450088 0.450088)
			(layers "F.Cu" "F.Mask" "F.Paste")
			(net "M_B_CPU1_SB_CB<6>")
		)
		(pad "BU65" smd circle
			(at 24.75992 10.889996 180)
			(size 0.450088 0.450088)
			(layers "F.Cu" "F.Mask" "F.Paste")
			(net "GND")
		)
		(pad "BU66" smd circle
			(at 25.699974 10.889996 180)
			(size 0.450088 0.450088)
			(layers "F.Cu" "F.Mask" "F.Paste")
			(net "M_F_CPU1_SB_CB<5>")
		)
		(pad "BU67" smd circle
			(at 26.640028 10.889996 180)
			(size 0.450088 0.450088)
			(layers "F.Cu" "F.Mask" "F.Paste")
			(net "M_F_CPU1_SB_CB<6>")
		)
		(pad "BU68" smd circle
			(at 27.580082 10.889996 180)
			(size 0.450088 0.450088)
			(layers "F.Cu" "F.Mask" "F.Paste")
			(net "GND")
		)
		(pad "BU69" smd circle
			(at 28.519882 10.889996 180)
			(size 0.450088 0.450088)
			(layers "F.Cu" "F.Mask" "F.Paste")
			(net "M_E_CPU1_SB_CB<5>")
		)
		(pad "BU70" smd circle
			(at 29.459936 10.889996 180)
			(size 0.450088 0.450088)
			(layers "F.Cu" "F.Mask" "F.Paste")
			(net "GND")
		)
		(pad "BU71" smd circle
			(at 30.39999 10.889996 180)
			(size 0.450088 0.450088)
			(layers "F.Cu" "F.Mask" "F.Paste")
			(net "M_E_CPU1_SB_CB<6>")
		)
		(pad "BU72" smd circle
			(at 31.340044 10.889996 180)
			(size 0.450088 0.450088)
			(layers "F.Cu" "F.Mask" "F.Paste")
			(net "GND")
		)
		(pad "BU73" smd circle
			(at 32.280098 10.889996 180)
			(size 0.450088 0.450088)
			(layers "F.Cu" "F.Mask" "F.Paste")
			(net "M_A_CPU1_SB_CB<5>")
		)
		(pad "BU74" smd circle
			(at 33.219898 10.889996 180)
			(size 0.450088 0.450088)
			(layers "F.Cu" "F.Mask" "F.Paste")
			(net "M_A_CPU1_SB_CB<6>")
		)
		(pad "BU75" smd circle
			(at 34.159952 10.889996 180)
			(size 0.450088 0.450088)
			(layers "F.Cu" "F.Mask" "F.Paste")
			(net "GND")
		)
		(pad "BV2" smd circle
			(at -33.990026 11.700002 180)
			(size 0.450088 0.450088)
			(layers "F.Cu" "F.Mask" "F.Paste")
			(net "M_G_CPU1_SB_DQS_DP<9>")
		)
		(pad "BV3" smd circle
			(at -33.049972 11.700002 180)
			(size 0.450088 0.450088)
			(layers "F.Cu" "F.Mask" "F.Paste")
			(net "GND")
		)
		(pad "BV4" smd circle
			(at -32.109918 11.700002 180)
			(size 0.450088 0.450088)
			(layers "F.Cu" "F.Mask" "F.Paste")
			(net "M_G_CPU1_SB_CB<7>")
		)
		(pad "BV5" smd circle
			(at -31.170118 11.700002 180)
			(size 0.450088 0.450088)
			(layers "F.Cu" "F.Mask" "F.Paste")
			(net "PVDD11_S3_P1")
		)
		(pad "BV6" smd circle
			(at -30.230064 11.700002 180)
			(size 0.450088 0.450088)
			(layers "F.Cu" "F.Mask" "F.Paste")
			(net "M_K_CPU1_SB_DQS_DP<9>")
		)
		(pad "BV7" smd circle
			(at -29.29001 11.700002 180)
			(size 0.450088 0.450088)
			(layers "F.Cu" "F.Mask" "F.Paste")
			(net "M_K_CPU1_SB_CB<7>")
		)
		(pad "BV8" smd circle
			(at -28.349956 11.700002 180)
			(size 0.450088 0.450088)
			(layers "F.Cu" "F.Mask" "F.Paste")
			(net "GND")
		)
		(pad "BV9" smd circle
			(at -27.409902 11.700002 180)
			(size 0.450088 0.450088)
			(layers "F.Cu" "F.Mask" "F.Paste")
			(net "M_L_CPU1_SB_DQS_DP<9>")
		)
		(pad "BV10" smd circle
			(at -26.470102 11.700002 180)
			(size 0.450088 0.450088)
			(layers "F.Cu" "F.Mask" "F.Paste")
			(net "GND")
		)
		(pad "BV11" smd circle
			(at -25.530048 11.700002 180)
			(size 0.450088 0.450088)
			(layers "F.Cu" "F.Mask" "F.Paste")
			(net "M_L_CPU1_SB_CB<7>")
		)
		(pad "BV12" smd circle
			(at -24.589994 11.700002 180)
			(size 0.450088 0.450088)
			(layers "F.Cu" "F.Mask" "F.Paste")
			(net "PVDD11_S3_P1")
		)
		(pad "BV13" smd circle
			(at -23.64994 11.700002 180)
			(size 0.450088 0.450088)
			(layers "F.Cu" "F.Mask" "F.Paste")
			(net "M_H_CPU1_SB_DQS_DP<9>")
		)
		(pad "BV14" smd circle
			(at -22.709886 11.700002 180)
			(size 0.450088 0.450088)
			(layers "F.Cu" "F.Mask" "F.Paste")
			(net "M_H_CPU1_SB_CB<7>")
		)
		(pad "BV15" smd circle
			(at -21.770086 11.700002 180)
			(size 0.450088 0.450088)
			(layers "F.Cu" "F.Mask" "F.Paste")
			(net "GND")
		)
		(pad "BV16" smd circle
			(at -20.830032 11.700002 180)
			(size 0.450088 0.450088)
			(layers "F.Cu" "F.Mask" "F.Paste")
			(net "M_J_CPU1_SB_DQS_DP<9>")
		)
		(pad "BV17" smd circle
			(at -19.889978 11.700002 180)
			(size 0.450088 0.450088)
			(layers "F.Cu" "F.Mask" "F.Paste")
			(net "GND")
		)
		(pad "BV18" smd circle
			(at -18.949924 11.700002 180)
			(size 0.450088 0.450088)
			(layers "F.Cu" "F.Mask" "F.Paste")
			(net "M_J_CPU1_SB_CB<7>")
		)
		(pad "BV19" smd circle
			(at -18.010124 11.700002 180)
			(size 0.450088 0.450088)
			(layers "F.Cu" "F.Mask" "F.Paste")
			(net "PVDD11_S3_P1")
		)
		(pad "BV20" smd circle
			(at -17.07007 11.700002 180)
			(size 0.450088 0.450088)
			(layers "F.Cu" "F.Mask" "F.Paste")
			(net "M_I_CPU1_SB_DQS_DP<9>")
		)
		(pad "BV21" smd circle
			(at -16.130016 11.700002 180)
			(size 0.450088 0.450088)
			(layers "F.Cu" "F.Mask" "F.Paste")
			(net "M_I_CPU1_SB_CB<7>")
		)
		(pad "BV22" smd circle
			(at -15.189962 11.700002 180)
			(size 0.450088 0.450088)
			(layers "F.Cu" "F.Mask" "F.Paste")
			(net "PVDD11_S3_P1")
		)
		(pad "BV23" smd circle
			(at -14.249908 11.700002 180)
			(size 0.450088 0.450088)
			(layers "F.Cu" "F.Mask" "F.Paste")
			(net "GND")
		)
		(pad "BV24" smd circle
			(at -13.310108 11.700002 180)
			(size 0.450088 0.450088)
			(layers "F.Cu" "F.Mask" "F.Paste")
			(net "GND")
		)
		(pad "BV25" smd circle
			(at -12.370054 11.700002 180)
			(size 0.450088 0.450088)
			(layers "F.Cu" "F.Mask" "F.Paste")
			(net "GND")
		)
		(pad "BV26" smd circle
			(at -11.43 11.700002 180)
			(size 0.450088 0.450088)
			(layers "F.Cu" "F.Mask" "F.Paste")
			(net "GND")
		)
		(pad "BV27" smd circle
			(at -10.489946 11.700002 180)
			(size 0.450088 0.450088)
			(layers "F.Cu" "F.Mask" "F.Paste")
			(net "GND")
		)
		(pad "BV28" smd circle
			(at -9.549892 11.700002 180)
			(size 0.450088 0.450088)
			(layers "F.Cu" "F.Mask" "F.Paste")
			(net "GND")
		)
		(pad "BV29" smd circle
			(at -8.610092 11.700002 180)
			(size 0.450088 0.450088)
			(layers "F.Cu" "F.Mask" "F.Paste")
			(net "GND")
		)
		(pad "BV30" smd circle
			(at -7.670038 11.700002 180)
			(size 0.450088 0.450088)
			(layers "F.Cu" "F.Mask" "F.Paste")
			(net "GND")
		)
		(pad "BV31" smd circle
			(at -6.729984 11.700002 180)
			(size 0.450088 0.450088)
			(layers "F.Cu" "F.Mask" "F.Paste")
			(net "GND")
		)
		(pad "BV32" smd circle
			(at -5.78993 11.700002 180)
			(size 0.450088 0.450088)
			(layers "F.Cu" "F.Mask" "F.Paste")
			(net "GND")
		)
		(pad "BV33" smd circle
			(at -4.849876 11.700002 180)
			(size 0.450088 0.450088)
			(layers "F.Cu" "F.Mask" "F.Paste")
			(net "GND")
		)
		(pad "BV34" smd circle
			(at -3.910076 11.700002 180)
			(size 0.450088 0.450088)
			(layers "F.Cu" "F.Mask" "F.Paste")
			(net "GND")
		)
		(pad "BV35" smd circle
			(at -2.970022 11.700002 180)
			(size 0.450088 0.450088)
			(layers "F.Cu" "F.Mask" "F.Paste")
			(net "P5E_CPU1_P2_TX_DN<1>")
		)
		(pad "BV36" smd circle
			(at -2.029968 11.700002 180)
			(size 0.450088 0.450088)
			(layers "F.Cu" "F.Mask" "F.Paste")
			(net "P5E_CPU1_P2_TX_DP<1>")
		)
		(pad "BV37" smd circle
			(at -1.089914 11.700002 180)
			(size 0.450088 0.450088)
			(layers "F.Cu" "F.Mask" "F.Paste")
			(net "GND")
		)
		(pad "BV39" smd circle
			(at 0.78994 11.700002 180)
			(size 0.450088 0.450088)
			(layers "F.Cu" "F.Mask" "F.Paste")
			(net "GND")
		)
		(pad "BV40" smd circle
			(at 1.729994 11.700002 180)
			(size 0.450088 0.450088)
			(layers "F.Cu" "F.Mask" "F.Paste")
			(net "P5E_CPU1_P0_RX_DP<14>")
		)
		(pad "BV41" smd circle
			(at 2.670048 11.700002 180)
			(size 0.450088 0.450088)
			(layers "F.Cu" "F.Mask" "F.Paste")
			(net "P5E_CPU1_P0_RX_DN<14>")
		)
		(pad "BV42" smd circle
			(at 3.610102 11.700002 180)
			(size 0.450088 0.450088)
			(layers "F.Cu" "F.Mask" "F.Paste")
			(net "GND")
		)
	)
)
